FILE_TYPE = CONNECTIVITY;
{Allegro Design Entry HDL 17.2-2016 S081 (4005846) 1/11/2022}
"PAGE_NUMBER" = 16;
0"NC";
1"PVNN_TERM_CPU0\g";
2"VSENSE_PVCCFA_EHV_FIVRA_CPU0_DN";
3"NC_CPU0_DDR01_VIEWDIG1"CDS_PHYS_NET_NAME"VSENSE_PVCCFA_EHV_CPU1_DP";
4"NC_CPU0_DDR45_VIEWDIG0";
5"NC_CPU0_DDR67_VIEWDIG0";
6"VSENSE_PVCCFA_EHV_CPU0_DN";
7"VSENSE_PVCCIN_CPU0_DN";
8"VSENSE_PVCCINFAON_CPU0_DN";
9"VSENSE_PVCCD_HV_CPU0_DP";
10"VSENSE_PVCCD_HV_CPU0_DN";
11"VSENSE_PVCCFA_EHV_FIVRA_CPU0_DP";
12"NC_CPU0_DDR01_VIEWDIG0";
13"NC_CPU0_DDR23_VIEWDIG0";
14"NC_CPU0_DDR23_VIEWDIG1"CDS_PHYS_NET_NAME"VSENSE_PVCCFA_EHV_CPU1_DP";
15"DBP_CPU_MBP1_GTL_N";
16"H_PMAX_TRIGGER_IO_CPU0";
17"NC_CPU0_DDR45_VIEWDIG1"CDS_PHYS_NET_NAME"VSENSE_PVCCFA_EHV_CPU1_DP";
18"NC_CPU0_DDR67_VIEWDIG1"CDS_PHYS_NET_NAME"VSENSE_PVCCFA_EHV_CPU1_DP";
19"VSENSE_PVCCFA_EHV_CPU0_DP";
20"VSENSE_PVCCINFAON_CPU0_DP";
21"VSENSE_PVCCIN_CPU0_DP";
22"NC_CPU0_LGSSPARE4";
23"NC_CPU0_THERMADA";
24"NC_CPU0_THERMADC";
25"TP_CPU0_A0_DEBUG_EN";
26"NC_CPU0_LGSSPARE0";
27"NC_CPU0_LGSSPARE5";
28"NC_CPU0_LGSSPARE1";
29"NC_CPU0_LGSSPARE2";
30"NC_CPU0_LGSSPARE3";
31"H_CPU0_RMCA_LVC1_R_N";
32"DBP_CPU0_HOOK9_MBP3_GTL_QS_R_N";
33"DBP_CPU0_HOOK8_MBP2_GTL_QS_R_N";
34"DBP_CPU0_MBP1_GTL_R_N";
35"DBP_CPU0_MBP0_GTL_R_N";
36"TP_CPU0_IFST_TRIG_LVC1_R";
37"TP_CPU0_IFST_KOT_LVC1_R";
38"TP_CPU0_IFST_DONE_LVC1_R";
39"DBP_CPU_MBP0_GTL_N";
40"DBP_CPU_HOOK8_MBP2_GTL_QS_N";
41"DBP_CPU_MBP1_GTL_N";
42"DBP_CPU_MBP0_GTL_N";
43"FM_PCH_TRIGGER1_N";
44"FM_PCH_TRIGGER0_N";
45"DBP_CPU_HOOK9_MBP3_GTL_QS_N";
%"SOCKET4677_AZIF0045P001C01CS"
"4","(1025,2875)","0","pure_quanta","I1";
;
PART_NUMBER"DGA^7000023"
PART_TYPE"SMLF"
MATERIAL"IO"
VALUE"SOCKET4677_AZIF0045-P001C01CS"
$LOCATION"U2"
CDS_LIB"pure_quanta"
NEEDS_NO_SIZE"TRUE"
CDS_LMAN_SYM_OUTLINE"-1100,850,1050,-850"
CDS_LOCATION"U2"
$SEC"4"
CDS_SEC"4";
"VSS_VCCIN_SENSE"
$PN"BC90"7;
"VSS_VCCINFAON_SENSE"
$PN"CE11"8;
"VSS_VCCFA_EHV_SENSE"
$PN"BA11"6;
"VSS_VCCFA_EHV_FIVRA_SENSE"
$PN"AT85"2;
"VSS_VCCD_HV_SENSE"
$PN"BN11"10;
"VCCIN_SENSE"
$PN"BD87"21;
"VCCINFAON_SENSE"
$PN"CA11"20;
"VCCFA_EHV_SENSE"
$PN"AU11"19;
"VCCFA_EHV_FIVRA_SENSE"
$PN"AY85"11;
"VCCD_HV_SENSE"
$PN"BU11"9;
"RSVD81"
$PN"CC64"22;
"RSVD9"
$PN"AU56"3;
"RSVD7"
$PN"AU33"14;
"RSVD18"
$PN"AV40"23;
"RSVD17"
$PN"AV38"24;
"RSVD16"
$PN"AV32"13;
"RSVD162"
$PN"H12"25;
"RSVD158"
$PN"DA45"5;
"RSVD153"
$PN"CY49"18;
"RSVD152"
$PN"CY38"17;
"RSVD151"
$PN"CY24"4;
"RSVD134"
$PN"CR60"26;
"RSVD129"
$PN"CP61"27;
"RSVD125"
$PN"CN60"28;
"RSVD139"
$PN"CU62"29;
"RSVD90"
$PN"CE62"30;
"RSVD10"
$PN"AU58"12;
"RMCA_N \B"
$PN"BH22"31;
"PMAX_TRIGGER_IO"
$PN"BD24"16;
"MBP3_N \B"
$PN"BK24"32;
"MBP2_N \B"
$PN"BJ23"33;
"MBP1_N \B"
$PN"BN25"34;
"MBP0_N \B"
$PN"BL23"35;
"RSVD49"
$PN"BF24"36;
"RSVD46"
$PN"BE23"37;
"RSVD37"
$PN"BC23"38;
%"Q_RES"
"1","(3725,2625)","0","pure_quanta","I19";
;
PART_NUMBER"CS11002FB07"
MATERIAL"CHIP"
TOLERANCE"1%"
VALUE"100"
PACK_TYPE"0402LF"
WATTAGE"1/16W"
$LOCATION"R22"
CDS_LIB"pure_quanta"
$LOCATION"R22"
CDS_LOCATION"R22"
$SEC"1"
CDS_SEC"1";
"B"
$PN"2"42;
"A"
$PN"1"35;
%"Q_RES"
"1","(3725,2575)","0","pure_quanta","I20";
;
PART_NUMBER"CS11002FB07"
MATERIAL"CHIP"
TOLERANCE"1%"
VALUE"100"
PACK_TYPE"0402LF"
WATTAGE"1/16W"
$LOCATION"R23"
CDS_LIB"pure_quanta"
$LOCATION"R23"
CDS_LOCATION"R23"
$SEC"1"
CDS_SEC"1";
"B"
$PN"2"41;
"A"
$PN"1"34;
%"Q_RES"
"1","(3725,2525)","0","pure_quanta","I25";
;
PART_NUMBER"CS01002FB07"
TOLERANCE"1%"
MATERIAL"CHIP"
VALUE"10"
PACK_TYPE"0402LF"
WATTAGE"1/16W"
$LOCATION"R24"
CDS_LIB"pure_quanta"
$LOCATION"R24"
CDS_LOCATION"R24"
$SEC"1"
CDS_SEC"1";
"B"
$PN"2"40;
"A"
$PN"1"33;
%"Q_RES"
"1","(3725,2475)","0","pure_quanta","I26";
;
PART_NUMBER"CS01002FB07"
VALUE"10"
MATERIAL"CHIP"
TOLERANCE"1%"
PACK_TYPE"0402LF"
WATTAGE"1/16W"
$LOCATION"R25"
CDS_LIB"pure_quanta"
$LOCATION"R25"
CDS_LOCATION"R25"
$SEC"1"
CDS_SEC"1";
"B"
$PN"2"45;
"A"
$PN"1"32;
%"UNIVERSAL_POWER"
"1","(2700,2075)","0","logical_power","I28";
;
HDL_POWER"PVNN_TERM_CPU0"
CDS_LIB"logical_power";
"A"1;
%"Q_RES"
"1","(4125,1375)","0","pure_quanta","I31";
;
PART_NUMBER"CS00002JB13"
PACK_TYPE"0402LF"
VALUE"0"
TOLERANCE"5%"
WATTAGE"1/16W"
MATERIAL"CHIP"
$LOCATION"R20"
CDS_LIB"pure_quanta"
$LOCATION"R20"
CDS_LOCATION"R20"
$SEC"1"
CDS_SEC"1";
"B"
$PN"2"44;
"A"
$PN"1"39;
%"Q_RES"
"1","(4125,1325)","0","pure_quanta","I32";
;
PART_NUMBER"CS00002JB13"
MATERIAL"CHIP"
TOLERANCE"5%"
VALUE"0"
PACK_TYPE"0402LF"
WATTAGE"1/16W"
$LOCATION"R21"
CDS_LIB"pure_quanta"
$LOCATION"R21"
CDS_LOCATION"R21"
$SEC"1"
CDS_SEC"1";
"B"
$PN"2"43;
"A"
$PN"1"15;
%"Q_RES"
"2","(2700,1750)","0","pure_quanta","I35";
;
PART_NUMBER"CS14992FB06"
WATTAGE"1/16W"
VALUE"499"
PACK_TYPE"0402LF"
TOLERANCE"1%"
MATERIAL"CHIP"
$LOCATION"R18"
CDS_LIB"pure_quanta"
$LOCATION"R18"
CDS_LOCATION"R18"
$SEC"1"
CDS_SEC"1";
"A"
$PN"1"1;
"B"
$PN"2"39;
%"Q_RES"
"2","(3075,1750)","0","pure_quanta","I36";
;
PART_NUMBER"CS14992FB06"
TOLERANCE"1%"
PACK_TYPE"0402LF"
VALUE"499"
MATERIAL"CHIP"
WATTAGE"1/16W"
$LOCATION"R19"
CDS_LIB"pure_quanta"
$LOCATION"R19"
CDS_LOCATION"R19"
$SEC"1"
CDS_SEC"1";
"A"
$PN"1"1;
"B"
$PN"2"15;
END.
